# T6G (Grand Teton) — schematic netlist excerpt (pin names and nets, part order shuffled) for the footprints in the layout excerpt that follows; sources: Cadence DE-HDL packaged netlist, KiCad conversion of 04192023_DAF0TMB3IC0_F0TG_MB_C_brd_V02_OCP.brd

R3481  Q_RES  33.2 1% CHIP  pkg 0402LF  page 81 : A = GPU_HMC_PRSNT_ISO_R_N ; B = GPU_HMC_PRSNT_ISO_N
C6708  Q_CAP_DIFFBUS  DIFF BUS_0.22UF 6.3V 20% X6S  pkg C0201  page 341 : \1\ = P5E_CPU1_P2_TX_BUF_C_DN<7> ; \2\ = P5E_CPU1_P2_TX_BUF_DN<7>
R1146  Q_RES  0 5% EMPTY  pkg 0402LF  page 142 : A = OCP_V3_2_AUX_PWR_EN_R2 ; B = HP_LVC3_OCP_V3_2_PWRGD_R1

(kicad_pcb
	(version 20260206)
	(generator "pcbnew")
	(generator_version "10.0")
	(general
		(thickness 1.6)
		(legacy_teardrops no)
	)
	(paper "A4")
	(title_block
		(title "04192023_DAF0TMB3IC0_F0TG_MB_C_brd_V02_OCP.brd")
		(comment 1 "Grand Teton / footprints 4634-4636 of 8354")
	)
	(layers
		(0 "F.Cu" signal "TOP")
		(4 "In1.Cu" signal "GND")
		(6 "In2.Cu" signal "IN1")
		(8 "In3.Cu" signal "GND1")
		(10 "In4.Cu" signal "IN2")
		(12 "In5.Cu" signal "GND2")
		(14 "In6.Cu" signal "IN3")
		(16 "In7.Cu" signal "GND3")
		(18 "In8.Cu" signal "VCC")
		(20 "In9.Cu" signal "VCC1")
		(22 "In10.Cu" signal "GND4")
		(24 "In11.Cu" signal "IN4")
		(26 "In12.Cu" signal "GND5")
		(28 "In13.Cu" signal "IN5")
		(30 "In14.Cu" signal "GND6")
		(32 "In15.Cu" signal "IN6")
		(34 "In16.Cu" signal "GND7")
		(2 "B.Cu" signal "BOTTOM")
		(9 "F.Adhes" user "F.Adhesive")
		(11 "B.Adhes" user "B.Adhesive")
		(13 "F.Paste" user "Package Geometry/Pastemask Top")
		(15 "B.Paste" user "Package Geometry/Pastemask Bottom")
		(5 "F.SilkS" user "Ref Des/Silkscreen Top")
		(7 "B.SilkS" user "Ref Des/Silkscreen Bottom")
		(1 "F.Mask" user "Board Geometry/Soldermask Top")
		(3 "B.Mask" user "Board Geometry/Soldermask Bottom")
		(17 "Dwgs.User" user "User.Drawings")
		(19 "Cmts.User" user "User.Comments")
		(21 "Eco1.User" user "User.Eco1")
		(23 "Eco2.User" user "User.Eco2")
		(25 "Edge.Cuts" user "Board Geometry/Outline")
		(27 "Margin" user)
		(31 "F.CrtYd" user "Package Geometry/Place Bound Top")
		(29 "B.CrtYd" user "Package Geometry/Place Bound Bottom")
		(35 "F.Fab" user "Ref Des/Assembly Top")
		(33 "B.Fab" user "Ref Des/Assembly Bottom")
	)
	(footprint ""
		(layer "F.Cu")
		(at 208.878932 -117.748812)
		(property "Reference" "R3481"
			(at 0 0 0)
			(layer "F.SilkS")
			(hide yes)
			(effects
				(font
					(size 1.27 1.27)
				)
			)
		)
		(property "Value" ""
			(at 0 0 0)
			(layer "F.Fab")
			(effects
				(font
					(size 1.27 1.27)
				)
			)
		)
		(duplicate_pad_numbers_are_jumpers no)
		(fp_line
			(start -0.7874 -0.4064)
			(end 0.7874 -0.4064)
			(stroke
				(width 0.1524)
				(type default)
			)
			(layer "F.SilkS")
		)
		(fp_line
			(start -0.7874 0.4064)
			(end -0.7874 -0.4064)
			(stroke
				(width 0.1524)
				(type default)
			)
			(layer "F.SilkS")
		)
		(fp_line
			(start 0.7874 -0.4064)
			(end 0.7874 0.4064)
			(stroke
				(width 0.1524)
				(type default)
			)
			(layer "F.SilkS")
		)
		(fp_line
			(start 0.7874 0.4064)
			(end -0.7874 0.4064)
			(stroke
				(width 0.1524)
				(type default)
			)
			(layer "F.SilkS")
		)
		(fp_line
			(start -0.67945 -0.305054)
			(end -0.12065 -0.305054)
			(stroke
				(width 0.1)
				(type default)
			)
			(layer "F.Fab")
		)
		(fp_line
			(start -0.67945 0.3048)
			(end -0.67945 -0.305054)
			(stroke
				(width 0.1)
				(type default)
			)
			(layer "F.Fab")
		)
		(fp_line
			(start -0.12065 -0.305054)
			(end -0.12065 -0.2794)
			(stroke
				(width 0.1)
				(type default)
			)
			(layer "F.Fab")
		)
		(fp_line
			(start -0.12065 -0.2794)
			(end 0.12065 -0.2794)
			(stroke
				(width 0.1)
				(type default)
			)
			(layer "F.Fab")
		)
		(fp_line
			(start -0.12065 0.2794)
			(end -0.12065 0.3048)
			(stroke
				(width 0.1)
				(type default)
			)
			(layer "F.Fab")
		)
		(fp_line
			(start -0.12065 0.3048)
			(end -0.67945 0.3048)
			(stroke
				(width 0.1)
				(type default)
			)
			(layer "F.Fab")
		)
		(fp_line
			(start 0.120396 0.2794)
			(end -0.12065 0.2794)
			(stroke
				(width 0.1)
				(type default)
			)
			(layer "F.Fab")
		)
		(fp_line
			(start 0.120396 0.3048)
			(end 0.120396 0.2794)
			(stroke
				(width 0.1)
				(type default)
			)
			(layer "F.Fab")
		)
		(fp_line
			(start 0.12065 -0.3048)
			(end 0.67945 -0.3048)
			(stroke
				(width 0.1)
				(type default)
			)
			(layer "F.Fab")
		)
		(fp_line
			(start 0.12065 -0.2794)
			(end 0.12065 -0.3048)
			(stroke
				(width 0.1)
				(type default)
			)
			(layer "F.Fab")
		)
		(fp_line
			(start 0.67945 -0.3048)
			(end 0.67945 0.3048)
			(stroke
				(width 0.1)
				(type default)
			)
			(layer "F.Fab")
		)
		(fp_line
			(start 0.67945 0.3048)
			(end 0.120396 0.3048)
			(stroke
				(width 0.1)
				(type default)
			)
			(layer "F.Fab")
		)
		(pad "1" smd circle
			(at -0.40005 0)
			(size 0 0)
			(layers "F.Cu" "F.Mask" "F.Paste")
			(net "GPU_HMC_PRSNT_ISO_R_N")
		)
		(pad "2" smd circle
			(at 0.40005 0)
			(size 0 0)
			(layers "F.Cu" "F.Mask" "F.Paste")
			(net "GPU_HMC_PRSNT_ISO_N")
		)
	)
	(footprint ""
		(layer "F.Cu")
		(at 136.311386 -408.517344 -90)
		(property "Reference" "C6708"
			(at 0 0 270)
			(layer "F.SilkS")
			(hide yes)
			(effects
				(font
					(size 1.27 1.27)
				)
			)
		)
		(property "Value" ""
			(at 0 0 270)
			(layer "F.Fab")
			(effects
				(font
					(size 1.27 1.27)
				)
			)
		)
		(duplicate_pad_numbers_are_jumpers no)
		(fp_line
			(start -0.299974 0.150114)
			(end -0.299974 -0.150114)
			(stroke
				(width 0.1)
				(type default)
			)
			(layer "F.Fab")
		)
		(fp_line
			(start 0.299974 0.150114)
			(end -0.299974 0.150114)
			(stroke
				(width 0.1)
				(type default)
			)
			(layer "F.Fab")
		)
		(fp_line
			(start -0.299974 -0.150114)
			(end 0.299974 -0.150114)
			(stroke
				(width 0.1)
				(type default)
			)
			(layer "F.Fab")
		)
		(fp_line
			(start 0.299974 -0.150114)
			(end 0.299974 0.150114)
			(stroke
				(width 0.1)
				(type default)
			)
			(layer "F.Fab")
		)
		(pad "1" smd rect
			(at -0.2667 0 270)
			(size 0.3048 0.381)
			(layers "F.Cu" "F.Mask" "F.Paste")
			(net "P5E_CPU1_P2_TX_BUF_C_DN<7>")
		)
		(pad "2" smd rect
			(at 0.2667 0 270)
			(size 0.3048 0.381)
			(layers "F.Cu" "F.Mask" "F.Paste")
			(net "P5E_CPU1_P2_TX_BUF_DN<7>")
		)
	)
	(footprint ""
		(layer "F.Cu")
		(at 70.739 -54.61 180)
		(property "Reference" "R1146"
			(at 0 0 180)
			(layer "F.SilkS")
			(hide yes)
			(effects
				(font
					(size 1.27 1.27)
				)
			)
		)
		(property "Value" ""
			(at 0 0 180)
			(layer "F.Fab")
			(effects
				(font
					(size 1.27 1.27)
				)
			)
		)
		(duplicate_pad_numbers_are_jumpers no)
		(fp_line
			(start 0.7874 0.4064)
			(end -0.7874 0.4064)
			(stroke
				(width 0.1524)
				(type default)
			)
			(layer "F.SilkS")
		)
		(fp_line
			(start 0.7874 -0.4064)
			(end 0.7874 0.4064)
			(stroke
				(width 0.1524)
				(type default)
			)
			(layer "F.SilkS")
		)
		(fp_line
			(start -0.7874 0.4064)
			(end -0.7874 -0.4064)
			(stroke
				(width 0.1524)
				(type default)
			)
			(layer "F.SilkS")
		)
		(fp_line
			(start -0.7874 -0.4064)
			(end 0.7874 -0.4064)
			(stroke
				(width 0.1524)
				(type default)
			)
			(layer "F.SilkS")
		)
		(fp_line
			(start 0.67945 0.3048)
			(end 0.120396 0.3048)
			(stroke
				(width 0.1)
				(type default)
			)
			(layer "F.Fab")
		)
		(fp_line
			(start 0.67945 -0.3048)
			(end 0.67945 0.3048)
			(stroke
				(width 0.1)
				(type default)
			)
			(layer "F.Fab")
		)
		(fp_line
			(start 0.12065 -0.2794)
			(end 0.12065 -0.3048)
			(stroke
				(width 0.1)
				(type default)
			)
			(layer "F.Fab")
		)
		(fp_line
			(start 0.12065 -0.3048)
			(end 0.67945 -0.3048)
			(stroke
				(width 0.1)
				(type default)
			)
			(layer "F.Fab")
		)
		(fp_line
			(start 0.120396 0.3048)
			(end 0.120396 0.2794)
			(stroke
				(width 0.1)
				(type default)
			)
			(layer "F.Fab")
		)
		(fp_line
			(start 0.120396 0.2794)
			(end -0.12065 0.2794)
			(stroke
				(width 0.1)
				(type default)
			)
			(layer "F.Fab")
		)
		(fp_line
			(start -0.12065 0.3048)
			(end -0.67945 0.3048)
			(stroke
				(width 0.1)
				(type default)
			)
			(layer "F.Fab")
		)
		(fp_line
			(start -0.12065 0.2794)
			(end -0.12065 0.3048)
			(stroke
				(width 0.1)
				(type default)
			)
			(layer "F.Fab")
		)
		(fp_line
			(start -0.12065 -0.2794)
			(end 0.12065 -0.2794)
			(stroke
				(width 0.1)
				(type default)
			)
			(layer "F.Fab")
		)
		(fp_line
			(start -0.12065 -0.305054)
			(end -0.12065 -0.2794)
			(stroke
				(width 0.1)
				(type default)
			)
			(layer "F.Fab")
		)
		(fp_line
			(start -0.67945 0.3048)
			(end -0.67945 -0.305054)
			(stroke
				(width 0.1)
				(type default)
			)
			(layer "F.Fab")
		)
		(fp_line
			(start -0.67945 -0.305054)
			(end -0.12065 -0.305054)
			(stroke
				(width 0.1)
				(type default)
			)
			(layer "F.Fab")
		)
		(pad "1" smd circle
			(at -0.40005 0 180)
			(size 0 0)
			(layers "F.Cu" "F.Mask" "F.Paste")
			(net "OCP_V3_2_AUX_PWR_EN_R2")
		)
		(pad "2" smd circle
			(at 0.40005 0 180)
			(size 0 0)
			(layers "F.Cu" "F.Mask" "F.Paste")
			(net "HP_LVC3_OCP_V3_2_PWRGD_R1")
		)
	)
)
